(kicad_pcb
	(version 20260206)
	(generator "pcbnew")
	(generator_version "10.0")
	(general
		(thickness 1.6)
		(legacy_teardrops no)
	)
	(paper "A4")
	(title_block
		(title "04192023_DAF0TMB3IC0_F0TG_MB_C_brd_V02_OCP.brd")
		(comment 1 "Grand Teton / footprints 4824-4830 of 8354")
	)
	(layers
		(0 "F.Cu" signal "TOP")
		(4 "In1.Cu" signal "GND")
		(6 "In2.Cu" signal "IN1")
		(8 "In3.Cu" signal "GND1")
		(10 "In4.Cu" signal "IN2")
		(12 "In5.Cu" signal "GND2")
		(14 "In6.Cu" signal "IN3")
		(16 "In7.Cu" signal "GND3")
		(18 "In8.Cu" signal "VCC")
		(20 "In9.Cu" signal "VCC1")
		(22 "In10.Cu" signal "GND4")
		(24 "In11.Cu" signal "IN4")
		(26 "In12.Cu" signal "GND5")
		(28 "In13.Cu" signal "IN5")
		(30 "In14.Cu" signal "GND6")
		(32 "In15.Cu" signal "IN6")
		(34 "In16.Cu" signal "GND7")
		(2 "B.Cu" signal "BOTTOM")
		(9 "F.Adhes" user "F.Adhesive")
		(11 "B.Adhes" user "B.Adhesive")
		(13 "F.Paste" user "Package Geometry/Pastemask Top")
		(15 "B.Paste" user "Package Geometry/Pastemask Bottom")
		(5 "F.SilkS" user "Ref Des/Silkscreen Top")
		(7 "B.SilkS" user "Ref Des/Silkscreen Bottom")
		(1 "F.Mask" user "Board Geometry/Soldermask Top")
		(3 "B.Mask" user "Board Geometry/Soldermask Bottom")
		(17 "Dwgs.User" user "User.Drawings")
		(19 "Cmts.User" user "User.Comments")
		(21 "Eco1.User" user "User.Eco1")
		(23 "Eco2.User" user "User.Eco2")
		(25 "Edge.Cuts" user "Board Geometry/Outline")
		(27 "Margin" user)
		(31 "F.CrtYd" user "Package Geometry/Place Bound Top")
		(29 "B.CrtYd" user "Package Geometry/Place Bound Bottom")
		(35 "F.Fab" user "Ref Des/Assembly Top")
		(33 "B.Fab" user "Ref Des/Assembly Bottom")
	)
	(footprint ""
		(layer "F.Cu")
		(at 110.565946 -52.86248 -90)
		(property "Reference" "R6304"
			(at 0 0 270)
			(layer "F.SilkS")
			(hide yes)
			(effects
				(font
					(size 1.27 1.27)
				)
			)
		)
		(property "Value" ""
			(at 0 0 270)
			(layer "F.Fab")
			(effects
				(font
					(size 1.27 1.27)
				)
			)
		)
		(duplicate_pad_numbers_are_jumpers no)
		(fp_line
			(start -0.7874 0.4064)
			(end -0.7874 -0.4064)
			(stroke
				(width 0.1524)
				(type default)
			)
			(layer "F.SilkS")
		)
		(fp_line
			(start 0.7874 0.4064)
			(end -0.7874 0.4064)
			(stroke
				(width 0.1524)
				(type default)
			)
			(layer "F.SilkS")
		)
		(fp_line
			(start -0.7874 -0.4064)
			(end 0.7874 -0.4064)
			(stroke
				(width 0.1524)
				(type default)
			)
			(layer "F.SilkS")
		)
		(fp_line
			(start 0.7874 -0.4064)
			(end 0.7874 0.4064)
			(stroke
				(width 0.1524)
				(type default)
			)
			(layer "F.SilkS")
		)
		(fp_line
			(start -0.67945 0.3048)
			(end -0.67945 -0.305054)
			(stroke
				(width 0.1)
				(type default)
			)
			(layer "F.Fab")
		)
		(fp_line
			(start -0.12065 0.3048)
			(end -0.67945 0.3048)
			(stroke
				(width 0.1)
				(type default)
			)
			(layer "F.Fab")
		)
		(fp_line
			(start 0.120396 0.3048)
			(end 0.120396 0.2794)
			(stroke
				(width 0.1)
				(type default)
			)
			(layer "F.Fab")
		)
		(fp_line
			(start 0.67945 0.3048)
			(end 0.120396 0.3048)
			(stroke
				(width 0.1)
				(type default)
			)
			(layer "F.Fab")
		)
		(fp_line
			(start -0.12065 0.2794)
			(end -0.12065 0.3048)
			(stroke
				(width 0.1)
				(type default)
			)
			(layer "F.Fab")
		)
		(fp_line
			(start 0.120396 0.2794)
			(end -0.12065 0.2794)
			(stroke
				(width 0.1)
				(type default)
			)
			(layer "F.Fab")
		)
		(fp_line
			(start -0.12065 -0.2794)
			(end 0.12065 -0.2794)
			(stroke
				(width 0.1)
				(type default)
			)
			(layer "F.Fab")
		)
		(fp_line
			(start 0.12065 -0.2794)
			(end 0.12065 -0.3048)
			(stroke
				(width 0.1)
				(type default)
			)
			(layer "F.Fab")
		)
		(fp_line
			(start 0.12065 -0.3048)
			(end 0.67945 -0.3048)
			(stroke
				(width 0.1)
				(type default)
			)
			(layer "F.Fab")
		)
		(fp_line
			(start 0.67945 -0.3048)
			(end 0.67945 0.3048)
			(stroke
				(width 0.1)
				(type default)
			)
			(layer "F.Fab")
		)
		(fp_line
			(start -0.67945 -0.305054)
			(end -0.12065 -0.305054)
			(stroke
				(width 0.1)
				(type default)
			)
			(layer "F.Fab")
		)
		(fp_line
			(start -0.12065 -0.305054)
			(end -0.12065 -0.2794)
			(stroke
				(width 0.1)
				(type default)
			)
			(layer "F.Fab")
		)
		(pad "1" smd circle
			(at -0.40005 0 270)
			(size 0 0)
			(layers "F.Cu" "F.Mask" "F.Paste")
			(net "USB_HUB2_TI_HS_SUSPEND")
		)
		(pad "2" smd circle
			(at 0.40005 0 270)
			(size 0 0)
			(layers "F.Cu" "F.Mask" "F.Paste")
			(net "USB_HUB2_TI_HS_SUSPEND_MRP_CFG_NON_REM")
		)
	)
	(footprint ""
		(layer "F.Cu")
		(at 144.36344 -31.58744 90)
		(property "Reference" "C6004"
			(at 0 0 90)
			(layer "F.SilkS")
			(hide yes)
			(effects
				(font
					(size 1.27 1.27)
				)
			)
		)
		(property "Value" ""
			(at 0 0 90)
			(layer "F.Fab")
			(effects
				(font
					(size 1.27 1.27)
				)
			)
		)
		(duplicate_pad_numbers_are_jumpers no)
		(fp_line
			(start 0.7874 -0.4064)
			(end 0.7874 0.4064)
			(stroke
				(width 0.1524)
				(type default)
			)
			(layer "F.SilkS")
		)
		(fp_line
			(start -0.7874 -0.4064)
			(end 0.7874 -0.4064)
			(stroke
				(width 0.1524)
				(type default)
			)
			(layer "F.SilkS")
		)
		(fp_line
			(start 0.7874 0.4064)
			(end -0.7874 0.4064)
			(stroke
				(width 0.1524)
				(type default)
			)
			(layer "F.SilkS")
		)
		(fp_line
			(start -0.7874 0.4064)
			(end -0.7874 -0.4064)
			(stroke
				(width 0.1524)
				(type default)
			)
			(layer "F.SilkS")
		)
		(fp_line
			(start 0.6858 -0.3048)
			(end 0.6858 0.3048)
			(stroke
				(width 0.1)
				(type default)
			)
			(layer "F.Fab")
		)
		(fp_line
			(start 0.1016 -0.3048)
			(end 0.6858 -0.3048)
			(stroke
				(width 0.1)
				(type default)
			)
			(layer "F.Fab")
		)
		(fp_line
			(start -0.1016 -0.3048)
			(end -0.1016 -0.2794)
			(stroke
				(width 0.1)
				(type default)
			)
			(layer "F.Fab")
		)
		(fp_line
			(start -0.6858 -0.3048)
			(end -0.1016 -0.3048)
			(stroke
				(width 0.1)
				(type default)
			)
			(layer "F.Fab")
		)
		(fp_line
			(start 0.1016 -0.2794)
			(end 0.1016 -0.3048)
			(stroke
				(width 0.1)
				(type default)
			)
			(layer "F.Fab")
		)
		(fp_line
			(start -0.1016 -0.2794)
			(end 0.1016 -0.2794)
			(stroke
				(width 0.1)
				(type default)
			)
			(layer "F.Fab")
		)
		(fp_line
			(start 0.1016 0.2794)
			(end -0.1016 0.2794)
			(stroke
				(width 0.1)
				(type default)
			)
			(layer "F.Fab")
		)
		(fp_line
			(start -0.1016 0.2794)
			(end -0.1016 0.3048)
			(stroke
				(width 0.1)
				(type default)
			)
			(layer "F.Fab")
		)
		(fp_line
			(start 0.6858 0.3048)
			(end 0.1016 0.3048)
			(stroke
				(width 0.1)
				(type default)
			)
			(layer "F.Fab")
		)
		(fp_line
			(start 0.1016 0.3048)
			(end 0.1016 0.2794)
			(stroke
				(width 0.1)
				(type default)
			)
			(layer "F.Fab")
		)
		(fp_line
			(start -0.1016 0.3048)
			(end -0.6858 0.3048)
			(stroke
				(width 0.1)
				(type default)
			)
			(layer "F.Fab")
		)
		(fp_line
			(start -0.6858 0.3048)
			(end -0.6858 -0.3048)
			(stroke
				(width 0.1)
				(type default)
			)
			(layer "F.Fab")
		)
		(pad "1" smd rect
			(at -0.40005 0 270)
			(size 0.4572 0.508)
			(layers "F.Cu" "F.Mask" "F.Paste")
			(net "USB3_CPU0_BMC_TX_DN")
		)
		(pad "2" smd rect
			(at 0.40005 0 270)
			(size 0.4572 0.508)
			(layers "F.Cu" "F.Mask" "F.Paste")
			(net "USB3_CPU0_BMC_TX_C1_DN")
		)
	)
	(footprint ""
		(layer "F.Cu")
		(at 59.8678 -36.083748 180)
		(property "Reference" "R4065"
			(at 0 0 180)
			(layer "F.SilkS")
			(hide yes)
			(effects
				(font
					(size 1.27 1.27)
				)
			)
		)
		(property "Value" ""
			(at 0 0 180)
			(layer "F.Fab")
			(effects
				(font
					(size 1.27 1.27)
				)
			)
		)
		(duplicate_pad_numbers_are_jumpers no)
		(fp_line
			(start 0.7874 0.4064)
			(end -0.7874 0.4064)
			(stroke
				(width 0.1524)
				(type default)
			)
			(layer "F.SilkS")
		)
		(fp_line
			(start 0.7874 -0.4064)
			(end 0.7874 0.4064)
			(stroke
				(width 0.1524)
				(type default)
			)
			(layer "F.SilkS")
		)
		(fp_line
			(start -0.7874 0.4064)
			(end -0.7874 -0.4064)
			(stroke
				(width 0.1524)
				(type default)
			)
			(layer "F.SilkS")
		)
		(fp_line
			(start -0.7874 -0.4064)
			(end 0.7874 -0.4064)
			(stroke
				(width 0.1524)
				(type default)
			)
			(layer "F.SilkS")
		)
		(fp_line
			(start 0.67945 0.3048)
			(end 0.120396 0.3048)
			(stroke
				(width 0.1)
				(type default)
			)
			(layer "F.Fab")
		)
		(fp_line
			(start 0.67945 -0.3048)
			(end 0.67945 0.3048)
			(stroke
				(width 0.1)
				(type default)
			)
			(layer "F.Fab")
		)
		(fp_line
			(start 0.12065 -0.2794)
			(end 0.12065 -0.3048)
			(stroke
				(width 0.1)
				(type default)
			)
			(layer "F.Fab")
		)
		(fp_line
			(start 0.12065 -0.3048)
			(end 0.67945 -0.3048)
			(stroke
				(width 0.1)
				(type default)
			)
			(layer "F.Fab")
		)
		(fp_line
			(start 0.120396 0.3048)
			(end 0.120396 0.2794)
			(stroke
				(width 0.1)
				(type default)
			)
			(layer "F.Fab")
		)
		(fp_line
			(start 0.120396 0.2794)
			(end -0.12065 0.2794)
			(stroke
				(width 0.1)
				(type default)
			)
			(layer "F.Fab")
		)
		(fp_line
			(start -0.12065 0.3048)
			(end -0.67945 0.3048)
			(stroke
				(width 0.1)
				(type default)
			)
			(layer "F.Fab")
		)
		(fp_line
			(start -0.12065 0.2794)
			(end -0.12065 0.3048)
			(stroke
				(width 0.1)
				(type default)
			)
			(layer "F.Fab")
		)
		(fp_line
			(start -0.12065 -0.2794)
			(end 0.12065 -0.2794)
			(stroke
				(width 0.1)
				(type default)
			)
			(layer "F.Fab")
		)
		(fp_line
			(start -0.12065 -0.305054)
			(end -0.12065 -0.2794)
			(stroke
				(width 0.1)
				(type default)
			)
			(layer "F.Fab")
		)
		(fp_line
			(start -0.67945 0.3048)
			(end -0.67945 -0.305054)
			(stroke
				(width 0.1)
				(type default)
			)
			(layer "F.Fab")
		)
		(fp_line
			(start -0.67945 -0.305054)
			(end -0.12065 -0.305054)
			(stroke
				(width 0.1)
				(type default)
			)
			(layer "F.Fab")
		)
		(pad "1" smd circle
			(at -0.40005 0 180)
			(size 0 0)
			(layers "F.Cu" "F.Mask" "F.Paste")
			(net "P12V_AUX")
		)
		(pad "2" smd circle
			(at 0.40005 0 180)
			(size 0 0)
			(layers "F.Cu" "F.Mask" "F.Paste")
			(net "P12V_OCP_2_EN_G")
		)
	)
	(footprint ""
		(layer "F.Cu")
		(at 145.501106 -408.517344 -90)
		(property "Reference" "C6714"
			(at 0 0 270)
			(layer "F.SilkS")
			(hide yes)
			(effects
				(font
					(size 1.27 1.27)
				)
			)
		)
		(property "Value" ""
			(at 0 0 270)
			(layer "F.Fab")
			(effects
				(font
					(size 1.27 1.27)
				)
			)
		)
		(duplicate_pad_numbers_are_jumpers no)
		(fp_line
			(start -0.299974 0.150114)
			(end -0.299974 -0.150114)
			(stroke
				(width 0.1)
				(type default)
			)
			(layer "F.Fab")
		)
		(fp_line
			(start 0.299974 0.150114)
			(end -0.299974 0.150114)
			(stroke
				(width 0.1)
				(type default)
			)
			(layer "F.Fab")
		)
		(fp_line
			(start -0.299974 -0.150114)
			(end 0.299974 -0.150114)
			(stroke
				(width 0.1)
				(type default)
			)
			(layer "F.Fab")
		)
		(fp_line
			(start 0.299974 -0.150114)
			(end 0.299974 0.150114)
			(stroke
				(width 0.1)
				(type default)
			)
			(layer "F.Fab")
		)
		(pad "1" smd rect
			(at -0.2667 0 270)
			(size 0.3048 0.381)
			(layers "F.Cu" "F.Mask" "F.Paste")
			(net "P5E_CPU1_P2_TX_BUF_C_DN<10>")
		)
		(pad "2" smd rect
			(at 0.2667 0 270)
			(size 0.3048 0.381)
			(layers "F.Cu" "F.Mask" "F.Paste")
			(net "P5E_CPU1_P2_TX_BUF_DN<10>")
		)
	)
	(footprint ""
		(layer "F.Cu")
		(at 101.770942 -145.377662 -90)
		(property "Reference" "R8180"
			(at 0 0 270)
			(layer "F.SilkS")
			(hide yes)
			(effects
				(font
					(size 1.27 1.27)
				)
			)
		)
		(property "Value" ""
			(at 0 0 270)
			(layer "F.Fab")
			(effects
				(font
					(size 1.27 1.27)
				)
			)
		)
		(duplicate_pad_numbers_are_jumpers no)
		(fp_line
			(start -0.7874 0.4064)
			(end -0.7874 -0.4064)
			(stroke
				(width 0.1524)
				(type default)
			)
			(layer "F.SilkS")
		)
		(fp_line
			(start 0.7874 0.4064)
			(end -0.7874 0.4064)
			(stroke
				(width 0.1524)
				(type default)
			)
			(layer "F.SilkS")
		)
		(fp_line
			(start -0.7874 -0.4064)
			(end 0.7874 -0.4064)
			(stroke
				(width 0.1524)
				(type default)
			)
			(layer "F.SilkS")
		)
		(fp_line
			(start 0.7874 -0.4064)
			(end 0.7874 0.4064)
			(stroke
				(width 0.1524)
				(type default)
			)
			(layer "F.SilkS")
		)
		(fp_line
			(start -0.67945 0.3048)
			(end -0.67945 -0.305054)
			(stroke
				(width 0.1)
				(type default)
			)
			(layer "F.Fab")
		)
		(fp_line
			(start -0.12065 0.3048)
			(end -0.67945 0.3048)
			(stroke
				(width 0.1)
				(type default)
			)
			(layer "F.Fab")
		)
		(fp_line
			(start 0.120396 0.3048)
			(end 0.120396 0.2794)
			(stroke
				(width 0.1)
				(type default)
			)
			(layer "F.Fab")
		)
		(fp_line
			(start 0.67945 0.3048)
			(end 0.120396 0.3048)
			(stroke
				(width 0.1)
				(type default)
			)
			(layer "F.Fab")
		)
		(fp_line
			(start -0.12065 0.2794)
			(end -0.12065 0.3048)
			(stroke
				(width 0.1)
				(type default)
			)
			(layer "F.Fab")
		)
		(fp_line
			(start 0.120396 0.2794)
			(end -0.12065 0.2794)
			(stroke
				(width 0.1)
				(type default)
			)
			(layer "F.Fab")
		)
		(fp_line
			(start -0.12065 -0.2794)
			(end 0.12065 -0.2794)
			(stroke
				(width 0.1)
				(type default)
			)
			(layer "F.Fab")
		)
		(fp_line
			(start 0.12065 -0.2794)
			(end 0.12065 -0.3048)
			(stroke
				(width 0.1)
				(type default)
			)
			(layer "F.Fab")
		)
		(fp_line
			(start 0.12065 -0.3048)
			(end 0.67945 -0.3048)
			(stroke
				(width 0.1)
				(type default)
			)
			(layer "F.Fab")
		)
		(fp_line
			(start 0.67945 -0.3048)
			(end 0.67945 0.3048)
			(stroke
				(width 0.1)
				(type default)
			)
			(layer "F.Fab")
		)
		(fp_line
			(start -0.67945 -0.305054)
			(end -0.12065 -0.305054)
			(stroke
				(width 0.1)
				(type default)
			)
			(layer "F.Fab")
		)
		(fp_line
			(start -0.12065 -0.305054)
			(end -0.12065 -0.2794)
			(stroke
				(width 0.1)
				(type default)
			)
			(layer "F.Fab")
		)
		(pad "1" smd circle
			(at -0.40005 0 270)
			(size 0 0)
			(layers "F.Cu" "F.Mask" "F.Paste")
			(net "PVDD18_S5_P1")
		)
		(pad "2" smd circle
			(at 0.40005 0 270)
			(size 0 0)
			(layers "F.Cu" "F.Mask" "F.Paste")
			(net "PVDDCR_CPU0_P1_OCP_N_R")
		)
	)
	(footprint ""
		(layer "F.Cu")
		(at 163.705794 -116.267484 180)
		(property "Reference" "R6141"
			(at 0 0 180)
			(layer "F.SilkS")
			(hide yes)
			(effects
				(font
					(size 1.27 1.27)
				)
			)
		)
		(property "Value" ""
			(at 0 0 180)
			(layer "F.Fab")
			(effects
				(font
					(size 1.27 1.27)
				)
			)
		)
		(duplicate_pad_numbers_are_jumpers no)
		(fp_line
			(start 0.7874 0.4064)
			(end -0.7874 0.4064)
			(stroke
				(width 0.1524)
				(type default)
			)
			(layer "F.SilkS")
		)
		(fp_line
			(start 0.7874 -0.4064)
			(end 0.7874 0.4064)
			(stroke
				(width 0.1524)
				(type default)
			)
			(layer "F.SilkS")
		)
		(fp_line
			(start -0.7874 0.4064)
			(end -0.7874 -0.4064)
			(stroke
				(width 0.1524)
				(type default)
			)
			(layer "F.SilkS")
		)
		(fp_line
			(start -0.7874 -0.4064)
			(end 0.7874 -0.4064)
			(stroke
				(width 0.1524)
				(type default)
			)
			(layer "F.SilkS")
		)
		(fp_line
			(start 0.67945 0.3048)
			(end 0.120396 0.3048)
			(stroke
				(width 0.1)
				(type default)
			)
			(layer "F.Fab")
		)
		(fp_line
			(start 0.67945 -0.3048)
			(end 0.67945 0.3048)
			(stroke
				(width 0.1)
				(type default)
			)
			(layer "F.Fab")
		)
		(fp_line
			(start 0.12065 -0.2794)
			(end 0.12065 -0.3048)
			(stroke
				(width 0.1)
				(type default)
			)
			(layer "F.Fab")
		)
		(fp_line
			(start 0.12065 -0.3048)
			(end 0.67945 -0.3048)
			(stroke
				(width 0.1)
				(type default)
			)
			(layer "F.Fab")
		)
		(fp_line
			(start 0.120396 0.3048)
			(end 0.120396 0.2794)
			(stroke
				(width 0.1)
				(type default)
			)
			(layer "F.Fab")
		)
		(fp_line
			(start 0.120396 0.2794)
			(end -0.12065 0.2794)
			(stroke
				(width 0.1)
				(type default)
			)
			(layer "F.Fab")
		)
		(fp_line
			(start -0.12065 0.3048)
			(end -0.67945 0.3048)
			(stroke
				(width 0.1)
				(type default)
			)
			(layer "F.Fab")
		)
		(fp_line
			(start -0.12065 0.2794)
			(end -0.12065 0.3048)
			(stroke
				(width 0.1)
				(type default)
			)
			(layer "F.Fab")
		)
		(fp_line
			(start -0.12065 -0.2794)
			(end 0.12065 -0.2794)
			(stroke
				(width 0.1)
				(type default)
			)
			(layer "F.Fab")
		)
		(fp_line
			(start -0.12065 -0.305054)
			(end -0.12065 -0.2794)
			(stroke
				(width 0.1)
				(type default)
			)
			(layer "F.Fab")
		)
		(fp_line
			(start -0.67945 0.3048)
			(end -0.67945 -0.305054)
			(stroke
				(width 0.1)
				(type default)
			)
			(layer "F.Fab")
		)
		(fp_line
			(start -0.67945 -0.305054)
			(end -0.12065 -0.305054)
			(stroke
				(width 0.1)
				(type default)
			)
			(layer "F.Fab")
		)
		(pad "1" smd circle
			(at -0.40005 0 180)
			(size 0 0)
			(layers "F.Cu" "F.Mask" "F.Paste")
			(net "FM_BOARD_BMC_SKU_ID4")
		)
		(pad "2" smd circle
			(at 0.40005 0 180)
			(size 0 0)
			(layers "F.Cu" "F.Mask" "F.Paste")
			(net "GND")
		)
	)
	(footprint ""
		(layer "F.Cu")
		(at 314.567316 -112.58677)
		(property "Reference" "R44"
			(at 0 0 0)
			(layer "F.SilkS")
			(hide yes)
			(effects
				(font
					(size 1.27 1.27)
				)
			)
		)
		(property "Value" ""
			(at 0 0 0)
			(layer "F.Fab")
			(effects
				(font
					(size 1.27 1.27)
				)
			)
		)
		(duplicate_pad_numbers_are_jumpers no)
		(fp_line
			(start -0.7874 -0.4064)
			(end 0.7874 -0.4064)
			(stroke
				(width 0.1524)
				(type default)
			)
			(layer "F.SilkS")
		)
		(fp_line
			(start -0.7874 0.4064)
			(end -0.7874 -0.4064)
			(stroke
				(width 0.1524)
				(type default)
			)
			(layer "F.SilkS")
		)
		(fp_line
			(start 0.7874 -0.4064)
			(end 0.7874 0.4064)
			(stroke
				(width 0.1524)
				(type default)
			)
			(layer "F.SilkS")
		)
		(fp_line
			(start 0.7874 0.4064)
			(end -0.7874 0.4064)
			(stroke
				(width 0.1524)
				(type default)
			)
			(layer "F.SilkS")
		)
		(fp_line
			(start -0.67945 -0.305054)
			(end -0.12065 -0.305054)
			(stroke
				(width 0.1)
				(type default)
			)
			(layer "F.Fab")
		)
		(fp_line
			(start -0.67945 0.3048)
			(end -0.67945 -0.305054)
			(stroke
				(width 0.1)
				(type default)
			)
			(layer "F.Fab")
		)
		(fp_line
			(start -0.12065 -0.305054)
			(end -0.12065 -0.2794)
			(stroke
				(width 0.1)
				(type default)
			)
			(layer "F.Fab")
		)
		(fp_line
			(start -0.12065 -0.2794)
			(end 0.12065 -0.2794)
			(stroke
				(width 0.1)
				(type default)
			)
			(layer "F.Fab")
		)
		(fp_line
			(start -0.12065 0.2794)
			(end -0.12065 0.3048)
			(stroke
				(width 0.1)
				(type default)
			)
			(layer "F.Fab")
		)
		(fp_line
			(start -0.12065 0.3048)
			(end -0.67945 0.3048)
			(stroke
				(width 0.1)
				(type default)
			)
			(layer "F.Fab")
		)
		(fp_line
			(start 0.120396 0.2794)
			(end -0.12065 0.2794)
			(stroke
				(width 0.1)
				(type default)
			)
			(layer "F.Fab")
		)
		(fp_line
			(start 0.120396 0.3048)
			(end 0.120396 0.2794)
			(stroke
				(width 0.1)
				(type default)
			)
			(layer "F.Fab")
		)
		(fp_line
			(start 0.12065 -0.3048)
			(end 0.67945 -0.3048)
			(stroke
				(width 0.1)
				(type default)
			)
			(layer "F.Fab")
		)
		(fp_line
			(start 0.12065 -0.2794)
			(end 0.12065 -0.3048)
			(stroke
				(width 0.1)
				(type default)
			)
			(layer "F.Fab")
		)
		(fp_line
			(start 0.67945 -0.3048)
			(end 0.67945 0.3048)
			(stroke
				(width 0.1)
				(type default)
			)
			(layer "F.Fab")
		)
		(fp_line
			(start 0.67945 0.3048)
			(end 0.120396 0.3048)
			(stroke
				(width 0.1)
				(type default)
			)
			(layer "F.Fab")
		)
		(pad "1" smd circle
			(at -0.40005 0)
			(size 0 0)
			(layers "F.Cu" "F.Mask" "F.Paste")
			(net "PD_CPU_FRU_WP")
		)
		(pad "2" smd circle
			(at 0.40005 0)
			(size 0 0)
			(layers "F.Cu" "F.Mask" "F.Paste")
			(net "GND")
		)
	)
)
